(kicad_pcb
	(version 20260206)
	(generator "pcbnew")
	(generator_version "10.0")
	(general
		(thickness 1.6)
		(legacy_teardrops no)
	)
	(paper "A4")
	(title_block
		(title "04192023_DAF0TMB3IC0_F0TG_MB_C_brd_V02_OCP.brd")
		(comment 1 "Grand Teton / footprints 6966-6971 of 8354")
	)
	(layers
		(0 "F.Cu" signal "TOP")
		(4 "In1.Cu" signal "GND")
		(6 "In2.Cu" signal "IN1")
		(8 "In3.Cu" signal "GND1")
		(10 "In4.Cu" signal "IN2")
		(12 "In5.Cu" signal "GND2")
		(14 "In6.Cu" signal "IN3")
		(16 "In7.Cu" signal "GND3")
		(18 "In8.Cu" signal "VCC")
		(20 "In9.Cu" signal "VCC1")
		(22 "In10.Cu" signal "GND4")
		(24 "In11.Cu" signal "IN4")
		(26 "In12.Cu" signal "GND5")
		(28 "In13.Cu" signal "IN5")
		(30 "In14.Cu" signal "GND6")
		(32 "In15.Cu" signal "IN6")
		(34 "In16.Cu" signal "GND7")
		(2 "B.Cu" signal "BOTTOM")
		(9 "F.Adhes" user "F.Adhesive")
		(11 "B.Adhes" user "B.Adhesive")
		(13 "F.Paste" user "Package Geometry/Pastemask Top")
		(15 "B.Paste" user "Package Geometry/Pastemask Bottom")
		(5 "F.SilkS" user "Ref Des/Silkscreen Top")
		(7 "B.SilkS" user "Ref Des/Silkscreen Bottom")
		(1 "F.Mask" user "Board Geometry/Soldermask Top")
		(3 "B.Mask" user "Board Geometry/Soldermask Bottom")
		(17 "Dwgs.User" user "User.Drawings")
		(19 "Cmts.User" user "User.Comments")
		(21 "Eco1.User" user "User.Eco1")
		(23 "Eco2.User" user "User.Eco2")
		(25 "Edge.Cuts" user "Board Geometry/Outline")
		(27 "Margin" user)
		(31 "F.CrtYd" user "Package Geometry/Place Bound Top")
		(29 "B.CrtYd" user "Package Geometry/Place Bound Bottom")
		(35 "F.Fab" user "Ref Des/Assembly Top")
		(33 "B.Fab" user "Ref Des/Assembly Bottom")
	)
	(footprint ""
		(layer "B.Cu")
		(at 374.186958 -205.101952 90)
		(property "Reference" "R404"
			(at 0 0 90)
			(layer "B.SilkS")
			(hide yes)
			(effects
				(font
					(size 1.27 1.27)
				)
				(justify mirror)
			)
		)
		(property "Value" ""
			(at 0 0 90)
			(layer "B.Fab")
			(effects
				(font
					(size 1.27 1.27)
				)
				(justify mirror)
			)
		)
		(duplicate_pad_numbers_are_jumpers no)
		(fp_line
			(start 0.7874 -0.4064)
			(end -0.7874 -0.4064)
			(stroke
				(width 0.1524)
				(type default)
			)
			(layer "B.SilkS")
		)
		(fp_line
			(start -0.7874 -0.4064)
			(end -0.7874 0.4064)
			(stroke
				(width 0.1524)
				(type default)
			)
			(layer "B.SilkS")
		)
		(fp_line
			(start 0.7874 0.4064)
			(end 0.7874 -0.4064)
			(stroke
				(width 0.1524)
				(type default)
			)
			(layer "B.SilkS")
		)
		(fp_line
			(start -0.7874 0.4064)
			(end 0.7874 0.4064)
			(stroke
				(width 0.1524)
				(type default)
			)
			(layer "B.SilkS")
		)
		(fp_line
			(start 0.67945 -0.305054)
			(end 0.12065 -0.305054)
			(stroke
				(width 0.1)
				(type default)
			)
			(layer "B.Fab")
		)
		(fp_line
			(start 0.12065 -0.305054)
			(end 0.12065 -0.2794)
			(stroke
				(width 0.1)
				(type default)
			)
			(layer "B.Fab")
		)
		(fp_line
			(start -0.12065 -0.3048)
			(end -0.67945 -0.3048)
			(stroke
				(width 0.1)
				(type default)
			)
			(layer "B.Fab")
		)
		(fp_line
			(start -0.67945 -0.3048)
			(end -0.67945 0.3048)
			(stroke
				(width 0.1)
				(type default)
			)
			(layer "B.Fab")
		)
		(fp_line
			(start 0.12065 -0.2794)
			(end -0.12065 -0.2794)
			(stroke
				(width 0.1)
				(type default)
			)
			(layer "B.Fab")
		)
		(fp_line
			(start -0.12065 -0.2794)
			(end -0.12065 -0.3048)
			(stroke
				(width 0.1)
				(type default)
			)
			(layer "B.Fab")
		)
		(fp_line
			(start 0.12065 0.2794)
			(end 0.12065 0.3048)
			(stroke
				(width 0.1)
				(type default)
			)
			(layer "B.Fab")
		)
		(fp_line
			(start -0.120396 0.2794)
			(end 0.12065 0.2794)
			(stroke
				(width 0.1)
				(type default)
			)
			(layer "B.Fab")
		)
		(fp_line
			(start 0.67945 0.3048)
			(end 0.67945 -0.305054)
			(stroke
				(width 0.1)
				(type default)
			)
			(layer "B.Fab")
		)
		(fp_line
			(start 0.12065 0.3048)
			(end 0.67945 0.3048)
			(stroke
				(width 0.1)
				(type default)
			)
			(layer "B.Fab")
		)
		(fp_line
			(start -0.120396 0.3048)
			(end -0.120396 0.2794)
			(stroke
				(width 0.1)
				(type default)
			)
			(layer "B.Fab")
		)
		(fp_line
			(start -0.67945 0.3048)
			(end -0.120396 0.3048)
			(stroke
				(width 0.1)
				(type default)
			)
			(layer "B.Fab")
		)
		(pad "1" smd circle
			(at 0.40005 0 270)
			(size 0 0)
			(layers "B.Cu" "B.Mask" "B.Paste")
			(net "JTAG_CPU0_R_TDO")
		)
		(pad "2" smd circle
			(at -0.40005 0 270)
			(size 0 0)
			(layers "B.Cu" "B.Mask" "B.Paste")
			(net "JTAG_CPU0_TDO")
		)
	)
	(footprint ""
		(layer "B.Cu")
		(at 350.318832 -257.930142 180)
		(property "Reference" "C2637"
			(at 0 0 0)
			(layer "B.SilkS")
			(hide yes)
			(effects
				(font
					(size 1.27 1.27)
				)
				(justify mirror)
			)
		)
		(property "Value" ""
			(at 0 0 0)
			(layer "B.Fab")
			(effects
				(font
					(size 1.27 1.27)
				)
				(justify mirror)
			)
		)
		(duplicate_pad_numbers_are_jumpers no)
		(fp_line
			(start 0.7874 0.4064)
			(end 0.7874 -0.4064)
			(stroke
				(width 0.1524)
				(type default)
			)
			(layer "B.SilkS")
		)
		(fp_line
			(start 0.7874 -0.4064)
			(end -0.7874 -0.4064)
			(stroke
				(width 0.1524)
				(type default)
			)
			(layer "B.SilkS")
		)
		(fp_line
			(start -0.7874 0.4064)
			(end 0.7874 0.4064)
			(stroke
				(width 0.1524)
				(type default)
			)
			(layer "B.SilkS")
		)
		(fp_line
			(start -0.7874 -0.4064)
			(end -0.7874 0.4064)
			(stroke
				(width 0.1524)
				(type default)
			)
			(layer "B.SilkS")
		)
		(fp_line
			(start 0.67945 0.3048)
			(end 0.67945 -0.305054)
			(stroke
				(width 0.1)
				(type default)
			)
			(layer "B.Fab")
		)
		(fp_line
			(start 0.67945 -0.305054)
			(end 0.12065 -0.305054)
			(stroke
				(width 0.1)
				(type default)
			)
			(layer "B.Fab")
		)
		(fp_line
			(start 0.12065 0.3048)
			(end 0.67945 0.3048)
			(stroke
				(width 0.1)
				(type default)
			)
			(layer "B.Fab")
		)
		(fp_line
			(start 0.12065 0.2794)
			(end 0.12065 0.3048)
			(stroke
				(width 0.1)
				(type default)
			)
			(layer "B.Fab")
		)
		(fp_line
			(start 0.12065 -0.2794)
			(end -0.12065 -0.2794)
			(stroke
				(width 0.1)
				(type default)
			)
			(layer "B.Fab")
		)
		(fp_line
			(start 0.12065 -0.305054)
			(end 0.12065 -0.2794)
			(stroke
				(width 0.1)
				(type default)
			)
			(layer "B.Fab")
		)
		(fp_line
			(start -0.120396 0.3048)
			(end -0.120396 0.2794)
			(stroke
				(width 0.1)
				(type default)
			)
			(layer "B.Fab")
		)
		(fp_line
			(start -0.120396 0.2794)
			(end 0.12065 0.2794)
			(stroke
				(width 0.1)
				(type default)
			)
			(layer "B.Fab")
		)
		(fp_line
			(start -0.12065 -0.2794)
			(end -0.12065 -0.3048)
			(stroke
				(width 0.1)
				(type default)
			)
			(layer "B.Fab")
		)
		(fp_line
			(start -0.12065 -0.3048)
			(end -0.67945 -0.3048)
			(stroke
				(width 0.1)
				(type default)
			)
			(layer "B.Fab")
		)
		(fp_line
			(start -0.67945 0.3048)
			(end -0.120396 0.3048)
			(stroke
				(width 0.1)
				(type default)
			)
			(layer "B.Fab")
		)
		(fp_line
			(start -0.67945 -0.3048)
			(end -0.67945 0.3048)
			(stroke
				(width 0.1)
				(type default)
			)
			(layer "B.Fab")
		)
		(pad "1" smd circle
			(at 0.40005 0)
			(size 0 0)
			(layers "B.Cu" "B.Mask" "B.Paste")
			(net "PVDDIO_P0")
		)
		(pad "2" smd circle
			(at -0.40005 0)
			(size 0 0)
			(layers "B.Cu" "B.Mask" "B.Paste")
			(net "GND")
		)
	)
	(footprint ""
		(layer "B.Cu")
		(at 118.432834 -245.487952 180)
		(property "Reference" "C2330"
			(at 0 0 0)
			(layer "B.SilkS")
			(hide yes)
			(effects
				(font
					(size 1.27 1.27)
				)
				(justify mirror)
			)
		)
		(property "Value" ""
			(at 0 0 0)
			(layer "B.Fab")
			(effects
				(font
					(size 1.27 1.27)
				)
				(justify mirror)
			)
		)
		(duplicate_pad_numbers_are_jumpers no)
		(fp_line
			(start 0.7874 0.4064)
			(end 0.7874 -0.4064)
			(stroke
				(width 0.1524)
				(type default)
			)
			(layer "B.SilkS")
		)
		(fp_line
			(start 0.7874 -0.4064)
			(end -0.7874 -0.4064)
			(stroke
				(width 0.1524)
				(type default)
			)
			(layer "B.SilkS")
		)
		(fp_line
			(start -0.7874 0.4064)
			(end 0.7874 0.4064)
			(stroke
				(width 0.1524)
				(type default)
			)
			(layer "B.SilkS")
		)
		(fp_line
			(start -0.7874 -0.4064)
			(end -0.7874 0.4064)
			(stroke
				(width 0.1524)
				(type default)
			)
			(layer "B.SilkS")
		)
		(fp_line
			(start 0.67945 0.3048)
			(end 0.67945 -0.305054)
			(stroke
				(width 0.1)
				(type default)
			)
			(layer "B.Fab")
		)
		(fp_line
			(start 0.67945 -0.305054)
			(end 0.12065 -0.305054)
			(stroke
				(width 0.1)
				(type default)
			)
			(layer "B.Fab")
		)
		(fp_line
			(start 0.12065 0.3048)
			(end 0.67945 0.3048)
			(stroke
				(width 0.1)
				(type default)
			)
			(layer "B.Fab")
		)
		(fp_line
			(start 0.12065 0.2794)
			(end 0.12065 0.3048)
			(stroke
				(width 0.1)
				(type default)
			)
			(layer "B.Fab")
		)
		(fp_line
			(start 0.12065 -0.2794)
			(end -0.12065 -0.2794)
			(stroke
				(width 0.1)
				(type default)
			)
			(layer "B.Fab")
		)
		(fp_line
			(start 0.12065 -0.305054)
			(end 0.12065 -0.2794)
			(stroke
				(width 0.1)
				(type default)
			)
			(layer "B.Fab")
		)
		(fp_line
			(start -0.120396 0.3048)
			(end -0.120396 0.2794)
			(stroke
				(width 0.1)
				(type default)
			)
			(layer "B.Fab")
		)
		(fp_line
			(start -0.120396 0.2794)
			(end 0.12065 0.2794)
			(stroke
				(width 0.1)
				(type default)
			)
			(layer "B.Fab")
		)
		(fp_line
			(start -0.12065 -0.2794)
			(end -0.12065 -0.3048)
			(stroke
				(width 0.1)
				(type default)
			)
			(layer "B.Fab")
		)
		(fp_line
			(start -0.12065 -0.3048)
			(end -0.67945 -0.3048)
			(stroke
				(width 0.1)
				(type default)
			)
			(layer "B.Fab")
		)
		(fp_line
			(start -0.67945 0.3048)
			(end -0.120396 0.3048)
			(stroke
				(width 0.1)
				(type default)
			)
			(layer "B.Fab")
		)
		(fp_line
			(start -0.67945 -0.3048)
			(end -0.67945 0.3048)
			(stroke
				(width 0.1)
				(type default)
			)
			(layer "B.Fab")
		)
		(pad "1" smd circle
			(at 0.40005 0)
			(size 0 0)
			(layers "B.Cu" "B.Mask" "B.Paste")
			(net "PVDDCR_CPU0_P1")
		)
		(pad "2" smd circle
			(at -0.40005 0)
			(size 0 0)
			(layers "B.Cu" "B.Mask" "B.Paste")
			(net "GND")
		)
	)
	(footprint ""
		(layer "B.Cu")
		(at 349.834454 -262.70331)
		(property "Reference" "C2574"
			(at 0 0 0)
			(layer "B.SilkS")
			(hide yes)
			(effects
				(font
					(size 1.27 1.27)
				)
				(justify mirror)
			)
		)
		(property "Value" ""
			(at 0 0 0)
			(layer "B.Fab")
			(effects
				(font
					(size 1.27 1.27)
				)
				(justify mirror)
			)
		)
		(duplicate_pad_numbers_are_jumpers no)
		(fp_line
			(start -0.7874 -0.4064)
			(end -0.7874 0.4064)
			(stroke
				(width 0.1524)
				(type default)
			)
			(layer "B.SilkS")
		)
		(fp_line
			(start -0.7874 0.4064)
			(end 0.7874 0.4064)
			(stroke
				(width 0.1524)
				(type default)
			)
			(layer "B.SilkS")
		)
		(fp_line
			(start 0.7874 -0.4064)
			(end -0.7874 -0.4064)
			(stroke
				(width 0.1524)
				(type default)
			)
			(layer "B.SilkS")
		)
		(fp_line
			(start 0.7874 0.4064)
			(end 0.7874 -0.4064)
			(stroke
				(width 0.1524)
				(type default)
			)
			(layer "B.SilkS")
		)
		(fp_line
			(start -0.67945 -0.3048)
			(end -0.67945 0.3048)
			(stroke
				(width 0.1)
				(type default)
			)
			(layer "B.Fab")
		)
		(fp_line
			(start -0.67945 0.3048)
			(end -0.120396 0.3048)
			(stroke
				(width 0.1)
				(type default)
			)
			(layer "B.Fab")
		)
		(fp_line
			(start -0.12065 -0.3048)
			(end -0.67945 -0.3048)
			(stroke
				(width 0.1)
				(type default)
			)
			(layer "B.Fab")
		)
		(fp_line
			(start -0.12065 -0.2794)
			(end -0.12065 -0.3048)
			(stroke
				(width 0.1)
				(type default)
			)
			(layer "B.Fab")
		)
		(fp_line
			(start -0.120396 0.2794)
			(end 0.12065 0.2794)
			(stroke
				(width 0.1)
				(type default)
			)
			(layer "B.Fab")
		)
		(fp_line
			(start -0.120396 0.3048)
			(end -0.120396 0.2794)
			(stroke
				(width 0.1)
				(type default)
			)
			(layer "B.Fab")
		)
		(fp_line
			(start 0.12065 -0.305054)
			(end 0.12065 -0.2794)
			(stroke
				(width 0.1)
				(type default)
			)
			(layer "B.Fab")
		)
		(fp_line
			(start 0.12065 -0.2794)
			(end -0.12065 -0.2794)
			(stroke
				(width 0.1)
				(type default)
			)
			(layer "B.Fab")
		)
		(fp_line
			(start 0.12065 0.2794)
			(end 0.12065 0.3048)
			(stroke
				(width 0.1)
				(type default)
			)
			(layer "B.Fab")
		)
		(fp_line
			(start 0.12065 0.3048)
			(end 0.67945 0.3048)
			(stroke
				(width 0.1)
				(type default)
			)
			(layer "B.Fab")
		)
		(fp_line
			(start 0.67945 -0.305054)
			(end 0.12065 -0.305054)
			(stroke
				(width 0.1)
				(type default)
			)
			(layer "B.Fab")
		)
		(fp_line
			(start 0.67945 0.3048)
			(end 0.67945 -0.305054)
			(stroke
				(width 0.1)
				(type default)
			)
			(layer "B.Fab")
		)
		(pad "1" smd circle
			(at 0.40005 0 180)
			(size 0 0)
			(layers "B.Cu" "B.Mask" "B.Paste")
			(net "PVDDCR_SOC_P0")
		)
		(pad "2" smd circle
			(at -0.40005 0 180)
			(size 0 0)
			(layers "B.Cu" "B.Mask" "B.Paste")
			(net "GND")
		)
	)
	(footprint ""
		(layer "B.Cu")
		(at 65.3796 -14.8336)
		(property "Reference" "C1839"
			(at 0 0 0)
			(layer "B.SilkS")
			(hide yes)
			(effects
				(font
					(size 1.27 1.27)
				)
				(justify mirror)
			)
		)
		(property "Value" ""
			(at 0 0 0)
			(layer "B.Fab")
			(effects
				(font
					(size 1.27 1.27)
				)
				(justify mirror)
			)
		)
		(duplicate_pad_numbers_are_jumpers no)
		(fp_line
			(start -0.7874 -0.4064)
			(end -0.7874 0.4064)
			(stroke
				(width 0.1524)
				(type default)
			)
			(layer "B.SilkS")
		)
		(fp_line
			(start -0.7874 0.4064)
			(end 0.7874 0.4064)
			(stroke
				(width 0.1524)
				(type default)
			)
			(layer "B.SilkS")
		)
		(fp_line
			(start 0.7874 -0.4064)
			(end -0.7874 -0.4064)
			(stroke
				(width 0.1524)
				(type default)
			)
			(layer "B.SilkS")
		)
		(fp_line
			(start 0.7874 0.4064)
			(end 0.7874 -0.4064)
			(stroke
				(width 0.1524)
				(type default)
			)
			(layer "B.SilkS")
		)
		(fp_line
			(start -0.67945 -0.3048)
			(end -0.67945 0.3048)
			(stroke
				(width 0.1)
				(type default)
			)
			(layer "B.Fab")
		)
		(fp_line
			(start -0.67945 0.3048)
			(end -0.120396 0.3048)
			(stroke
				(width 0.1)
				(type default)
			)
			(layer "B.Fab")
		)
		(fp_line
			(start -0.12065 -0.3048)
			(end -0.67945 -0.3048)
			(stroke
				(width 0.1)
				(type default)
			)
			(layer "B.Fab")
		)
		(fp_line
			(start -0.12065 -0.2794)
			(end -0.12065 -0.3048)
			(stroke
				(width 0.1)
				(type default)
			)
			(layer "B.Fab")
		)
		(fp_line
			(start -0.120396 0.2794)
			(end 0.12065 0.2794)
			(stroke
				(width 0.1)
				(type default)
			)
			(layer "B.Fab")
		)
		(fp_line
			(start -0.120396 0.3048)
			(end -0.120396 0.2794)
			(stroke
				(width 0.1)
				(type default)
			)
			(layer "B.Fab")
		)
		(fp_line
			(start 0.12065 -0.305054)
			(end 0.12065 -0.2794)
			(stroke
				(width 0.1)
				(type default)
			)
			(layer "B.Fab")
		)
		(fp_line
			(start 0.12065 -0.2794)
			(end -0.12065 -0.2794)
			(stroke
				(width 0.1)
				(type default)
			)
			(layer "B.Fab")
		)
		(fp_line
			(start 0.12065 0.2794)
			(end 0.12065 0.3048)
			(stroke
				(width 0.1)
				(type default)
			)
			(layer "B.Fab")
		)
		(fp_line
			(start 0.12065 0.3048)
			(end 0.67945 0.3048)
			(stroke
				(width 0.1)
				(type default)
			)
			(layer "B.Fab")
		)
		(fp_line
			(start 0.67945 -0.305054)
			(end 0.12065 -0.305054)
			(stroke
				(width 0.1)
				(type default)
			)
			(layer "B.Fab")
		)
		(fp_line
			(start 0.67945 0.3048)
			(end 0.67945 -0.305054)
			(stroke
				(width 0.1)
				(type default)
			)
			(layer "B.Fab")
		)
		(pad "1" smd circle
			(at 0.40005 0 180)
			(size 0 0)
			(layers "B.Cu" "B.Mask" "B.Paste")
			(net "P12V_OCP_V3_2_R")
		)
		(pad "2" smd circle
			(at -0.40005 0 180)
			(size 0 0)
			(layers "B.Cu" "B.Mask" "B.Paste")
			(net "GND")
		)
	)
	(footprint ""
		(layer "B.Cu")
		(at 433.05222 -418.942266 180)
		(property "Reference" ""
			(at 0 0 0)
			(layer "B.SilkS")
			(hide yes)
			(effects
				(font
					(size 1.27 1.27)
				)
				(justify mirror)
			)
		)
		(property "Value" ""
			(at 0 0 0)
			(layer "B.Fab")
			(effects
				(font
					(size 1.27 1.27)
				)
				(justify mirror)
			)
		)
		(duplicate_pad_numbers_are_jumpers no)
		(pad "1" smd circle
			(at 0 0)
			(size 0.9906 0.9906)
			(layers "B.Cu" "B.Mask" "B.Paste")
			(net "Net_655")
		)
		(zone
			(layer "B.Cu")
			(hatch none 0.5)
			(connect_pads
				(clearance 0)
			)
			(min_thickness 0.25)
			(keepout
				(tracks not_allowed)
				(vias allowed)
				(pads allowed)
				(copperpour not_allowed)
				(footprints allowed)
			)
			(placement
				(enabled no)
				(sheetname "")
			)
			(fill
				(thermal_gap 0.5)
				(thermal_bridge_width 0.5)
				(island_removal_mode 0)
			)
			(polygon
				(pts
					(arc
						(start 434.67782 -418.942266)
						(mid 431.42662 -418.942266)
						(end 434.67782 -418.942266)
					)
				)
			)
		)
	)
)
